(kicad_pcb
	(version 20241229)
	(generator "pcbnew")
	(generator_version "9.0")
	(general
		(thickness 1.6642)
		(legacy_teardrops no)
	)
	(paper "A3")
	(title_block
		(title "PolarFire SoM")
		(date "2025-07-22")
		(rev "1.1.4")
		(company "Antmicro Ltd")
		(comment 1 "www.antmicro.com")
		(comment 9 "footprint 127 of 470 (J4), pads 1-94 of 104")
	)
	(layers
		(0 "F.Cu" mixed)
		(4 "In1.Cu" power)
		(6 "In2.Cu" signal)
		(8 "In3.Cu" power)
		(10 "In4.Cu" signal)
		(12 "In5.Cu" power)
		(14 "In6.Cu" power)
		(16 "In7.Cu" signal)
		(18 "In8.Cu" power)
		(20 "In9.Cu" signal)
		(22 "In10.Cu" power)
		(24 "In11.Cu" signal)
		(26 "In12.Cu" signal)
		(2 "B.Cu" mixed)
		(9 "F.Adhes" user "F.Adhesive")
		(11 "B.Adhes" user "B.Adhesive")
		(13 "F.Paste" user)
		(15 "B.Paste" user)
		(5 "F.SilkS" user "F.Silkscreen")
		(7 "B.SilkS" user "B.Silkscreen")
		(1 "F.Mask" user)
		(3 "B.Mask" user)
		(17 "Dwgs.User" user "User.Drawings")
		(19 "Cmts.User" user "User.Comments")
		(21 "Eco1.User" user "User.Eco1")
		(23 "Eco2.User" user "User.Eco2")
		(25 "Edge.Cuts" user)
		(27 "Margin" user)
		(31 "F.CrtYd" user "F.Courtyard")
		(29 "B.CrtYd" user "B.Courtyard")
		(35 "F.Fab" user)
		(33 "B.Fab" user)
	)
	(footprint "antmicro-footprints:Conn_Plug_Hirose_DF40_2x50_DF40C-100DP-0.4V"
		(layer "B.Cu")
		(at 199.52 152.838 180)
		(property "Reference" "J4"
			(at -10.91 1.838 0)
			(layer "B.SilkS")
			(effects
				(font
					(size 0.7 0.7)
					(thickness 0.15)
				)
				(justify left bottom mirror)
			)
		)
		(property "Value" "Plug_Hirose_DF40_2x50_DF40C-100DP-0.4V"
			(at 0.001 -2.8 0)
			(layer "B.Fab")
			(hide yes)
			(effects
				(font
					(size 0.7 0.7)
					(thickness 0.15)
				)
				(justify left bottom mirror)
			)
		)
		(property "Datasheet" "https://www.hirose.com/en/product/document?clcode=CL0684-4032-1-51&productname=DF40C-100DP-0.4V(51)&series=DF40&documenttype=2DDrawing&lang=en&documentid=0001001212"
			(at 0 0 180)
			(layer "F.Fab")
			(hide yes)
			(effects
				(font
					(size 1.27 1.27)
					(thickness 0.15)
				)
			)
		)
		(property "Description" "Mezzanine Connector, Header, 0.4 mm, 2 Rows, 100 Contacts, Surface Mount, Phosphor Bronze"
			(at 0 0 180)
			(layer "F.Fab")
			(hide yes)
			(effects
				(font
					(size 1.27 1.27)
					(thickness 0.15)
				)
			)
		)
		(property "Author" "Antmicro"
			(at 399.04 305.676 0)
			(layer "B.Fab")
			(hide yes)
			(effects
				(font
					(size 1 1)
					(thickness 0.15)
				)
				(justify mirror)
			)
		)
		(property "License" "Apache-2.0"
			(at 399.04 305.676 0)
			(layer "B.Fab")
			(hide yes)
			(effects
				(font
					(size 1 1)
					(thickness 0.15)
				)
				(justify mirror)
			)
		)
		(property "MPN" "DF40C-100DP-0.4V(51)"
			(at 399.04 305.676 0)
			(layer "B.Fab")
			(hide yes)
			(effects
				(font
					(size 1 1)
					(thickness 0.15)
				)
				(justify mirror)
			)
		)
		(property "Manufacturer" "Hirose Electric"
			(at 399.04 305.676 0)
			(layer "B.Fab")
			(hide yes)
			(effects
				(font
					(size 1 1)
					(thickness 0.15)
				)
				(justify mirror)
			)
		)
		(property "Pitch" "0.4 mm"
			(at 399.04 305.676 0)
			(layer "B.Fab")
			(hide yes)
			(effects
				(font
					(size 1 1)
					(thickness 0.15)
				)
				(justify mirror)
			)
		)
		(sheetname "/Bottom Connector/")
		(sheetfile "bottom-connector.kicad_sch")
		(attr smd)
		(pad "1" smd rect
			(at -9.798 1.377 180)
			(size 0.23 0.66)
			(layers "B.Cu" "B.Mask" "B.Paste")
			(net 62 "USB_OTG_ID")
			(pintype "passive")
		)
		(pad "2" smd rect
			(at -9.798 -1.333 180)
			(size 0.23 0.66)
			(layers "B.Cu" "B.Mask" "B.Paste")
			(net 200 "PCIe_CLK_nREQ")
			(pintype "passive")
		)
		(pad "3" smd rect
			(at -9.399 1.377 180)
			(size 0.23 0.66)
			(layers "B.Cu" "B.Mask" "B.Paste")
			(net 15 "/Bottom Connector/CONN.D_N")
			(pintype "passive")
		)
		(pad "4" smd rect
			(at -9.399 -1.333 180)
			(size 0.23 0.66)
			(layers "B.Cu" "B.Mask" "B.Paste")
			(net 65 "unconnected-(J4-Pad4)")
			(pintype "passive+no_connect")
		)
		(pad "5" smd rect
			(at -8.998 1.377 180)
			(size 0.23 0.66)
			(layers "B.Cu" "B.Mask" "B.Paste")
			(net 16 "/Bottom Connector/CONN.D_P")
			(pintype "passive")
		)
		(pad "6" smd rect
			(at -8.998 -1.333 180)
			(size 0.23 0.66)
			(layers "B.Cu" "B.Mask" "B.Paste")
			(net 67 "unconnected-(J4-Pad6)")
			(pintype "passive+no_connect")
		)
		(pad "7" smd rect
			(at -8.598 1.377 180)
			(size 0.23 0.66)
			(layers "B.Cu" "B.Mask" "B.Paste")
			(net 417 "GND")
			(pintype "passive")
		)
		(pad "8" smd rect
			(at -8.598 -1.333 180)
			(size 0.23 0.66)
			(layers "B.Cu" "B.Mask" "B.Paste")
			(net 417 "GND")
			(pintype "passive")
		)
		(pad "9" smd rect
			(at -8.196 1.377 180)
			(size 0.23 0.66)
			(layers "B.Cu" "B.Mask" "B.Paste")
			(net 202 "PCIe_nRST")
			(pintype "passive")
		)
		(pad "10" smd rect
			(at -8.196 -1.333 180)
			(size 0.23 0.66)
			(layers "B.Cu" "B.Mask" "B.Paste")
			(net 5 "/Bottom Connector/PCIE.CLK_P")
			(pintype "passive")
		)
		(pad "11" smd rect
			(at -7.798 1.377 180)
			(size 0.23 0.66)
			(layers "B.Cu" "B.Mask" "B.Paste")
			(net 69 "unconnected-(J4-Pad11)")
			(pintype "passive+no_connect")
		)
		(pad "12" smd rect
			(at -7.798 -1.333 180)
			(size 0.23 0.66)
			(layers "B.Cu" "B.Mask" "B.Paste")
			(net 4 "/Bottom Connector/PCIE.CLK_N")
			(pintype "passive")
		)
		(pad "13" smd rect
			(at -7.399 1.377 180)
			(size 0.23 0.66)
			(layers "B.Cu" "B.Mask" "B.Paste")
			(net 417 "GND")
			(pintype "passive")
		)
		(pad "14" smd rect
			(at -7.399 -1.333 180)
			(size 0.23 0.66)
			(layers "B.Cu" "B.Mask" "B.Paste")
			(net 417 "GND")
			(pintype "passive")
		)
		(pad "15" smd rect
			(at -6.998 1.377 180)
			(size 0.23 0.66)
			(layers "B.Cu" "B.Mask" "B.Paste")
			(net 99 "/Bottom Connector/CAM1.D0_N")
			(pintype "passive")
		)
		(pad "16" smd rect
			(at -6.998 -1.333 180)
			(size 0.23 0.66)
			(layers "B.Cu" "B.Mask" "B.Paste")
			(net 102 "/Bottom Connector/PCIE.RXD0_P")
			(pintype "passive")
		)
		(pad "17" smd rect
			(at -6.598 1.377 180)
			(size 0.23 0.66)
			(layers "B.Cu" "B.Mask" "B.Paste")
			(net 104 "/Bottom Connector/CAM1.D0_P")
			(pintype "passive")
		)
		(pad "18" smd rect
			(at -6.598 -1.333 180)
			(size 0.23 0.66)
			(layers "B.Cu" "B.Mask" "B.Paste")
			(net 105 "/Bottom Connector/PCIE.RXD0_N")
			(pintype "passive")
		)
		(pad "19" smd rect
			(at -6.199 1.377 180)
			(size 0.23 0.66)
			(layers "B.Cu" "B.Mask" "B.Paste")
			(net 417 "GND")
			(pintype "passive")
		)
		(pad "20" smd rect
			(at -6.199 -1.333 180)
			(size 0.23 0.66)
			(layers "B.Cu" "B.Mask" "B.Paste")
			(net 417 "GND")
			(pintype "passive")
		)
		(pad "21" smd rect
			(at -5.798 1.377 180)
			(size 0.23 0.66)
			(layers "B.Cu" "B.Mask" "B.Paste")
			(net 106 "/Bottom Connector/CAM1.D1_N")
			(pintype "passive")
		)
		(pad "22" smd rect
			(at -5.798 -1.333 180)
			(size 0.23 0.66)
			(layers "B.Cu" "B.Mask" "B.Paste")
			(net 19 "/Bottom Connector/PCIE.TXD0_P")
			(pintype "passive")
		)
		(pad "23" smd rect
			(at -5.399 1.377 180)
			(size 0.23 0.66)
			(layers "B.Cu" "B.Mask" "B.Paste")
			(net 107 "/Bottom Connector/CAM1.D1_P")
			(pintype "passive")
		)
		(pad "24" smd rect
			(at -5.399 -1.333 180)
			(size 0.23 0.66)
			(layers "B.Cu" "B.Mask" "B.Paste")
			(net 33 "/Bottom Connector/PCIE.TXD0_N")
			(pintype "passive")
		)
		(pad "25" smd rect
			(at -4.998 1.377 180)
			(size 0.23 0.66)
			(layers "B.Cu" "B.Mask" "B.Paste")
			(net 417 "GND")
			(pintype "passive")
		)
		(pad "26" smd rect
			(at -4.998 -1.333 180)
			(size 0.23 0.66)
			(layers "B.Cu" "B.Mask" "B.Paste")
			(net 417 "GND")
			(pintype "passive")
		)
		(pad "27" smd rect
			(at -4.598 1.377 180)
			(size 0.23 0.66)
			(layers "B.Cu" "B.Mask" "B.Paste")
			(net 108 "/Bottom Connector/CAM1.C_N")
			(pintype "passive")
		)
		(pad "28" smd rect
			(at -4.598 -1.333 180)
			(size 0.23 0.66)
			(layers "B.Cu" "B.Mask" "B.Paste")
			(net 109 "/Bottom Connector/CAM0.D0_N")
			(pintype "passive")
		)
		(pad "29" smd rect
			(at -4.199 1.377 180)
			(size 0.23 0.66)
			(layers "B.Cu" "B.Mask" "B.Paste")
			(net 110 "/Bottom Connector/CAM1.C_P")
			(pintype "passive")
		)
		(pad "30" smd rect
			(at -4.199 -1.333 180)
			(size 0.23 0.66)
			(layers "B.Cu" "B.Mask" "B.Paste")
			(net 111 "/Bottom Connector/CAM0.D0_P")
			(pintype "passive")
		)
		(pad "31" smd rect
			(at -3.798 1.377 180)
			(size 0.23 0.66)
			(layers "B.Cu" "B.Mask" "B.Paste")
			(net 417 "GND")
			(pintype "passive")
		)
		(pad "32" smd rect
			(at -3.798 -1.333 180)
			(size 0.23 0.66)
			(layers "B.Cu" "B.Mask" "B.Paste")
			(net 417 "GND")
			(pintype "passive")
		)
		(pad "33" smd rect
			(at -3.397 1.377 180)
			(size 0.23 0.66)
			(layers "B.Cu" "B.Mask" "B.Paste")
			(net 112 "/Bottom Connector/CAM1.D2_N")
			(pintype "passive")
		)
		(pad "34" smd rect
			(at -3.397 -1.333 180)
			(size 0.23 0.66)
			(layers "B.Cu" "B.Mask" "B.Paste")
			(net 113 "/Bottom Connector/CAM0.D1_N")
			(pintype "passive")
		)
		(pad "35" smd rect
			(at -2.998 1.377 180)
			(size 0.23 0.66)
			(layers "B.Cu" "B.Mask" "B.Paste")
			(net 114 "/Bottom Connector/CAM1.D2_P")
			(pintype "passive")
		)
		(pad "36" smd rect
			(at -2.998 -1.333 180)
			(size 0.23 0.66)
			(layers "B.Cu" "B.Mask" "B.Paste")
			(net 115 "/Bottom Connector/CAM0.D1_P")
			(pintype "passive")
		)
		(pad "37" smd rect
			(at -2.597 1.377 180)
			(size 0.23 0.66)
			(layers "B.Cu" "B.Mask" "B.Paste")
			(net 417 "GND")
			(pintype "passive")
		)
		(pad "38" smd rect
			(at -2.597 -1.333 180)
			(size 0.23 0.66)
			(layers "B.Cu" "B.Mask" "B.Paste")
			(net 417 "GND")
			(pintype "passive")
		)
		(pad "39" smd rect
			(at -2.199 1.377 180)
			(size 0.23 0.66)
			(layers "B.Cu" "B.Mask" "B.Paste")
			(net 116 "/Bottom Connector/CAM1.D3_N")
			(pintype "passive")
		)
		(pad "40" smd rect
			(at -2.199 -1.333 180)
			(size 0.23 0.66)
			(layers "B.Cu" "B.Mask" "B.Paste")
			(net 118 "/Bottom Connector/CAM0.C_N")
			(pintype "passive")
		)
		(pad "41" smd rect
			(at -1.798 1.377 180)
			(size 0.23 0.66)
			(layers "B.Cu" "B.Mask" "B.Paste")
			(net 119 "/Bottom Connector/CAM1.D3_P")
			(pintype "passive")
		)
		(pad "42" smd rect
			(at -1.798 -1.333 180)
			(size 0.23 0.66)
			(layers "B.Cu" "B.Mask" "B.Paste")
			(net 120 "/Bottom Connector/CAM0.C_P")
			(pintype "passive")
		)
		(pad "43" smd rect
			(at -1.397 1.377 180)
			(size 0.23 0.66)
			(layers "B.Cu" "B.Mask" "B.Paste")
			(net 410 "Net-(Q3-D)")
			(pintype "passive")
		)
		(pad "44" smd rect
			(at -1.397 -1.333 180)
			(size 0.23 0.66)
			(layers "B.Cu" "B.Mask" "B.Paste")
			(net 417 "GND")
			(pintype "passive")
		)
		(pad "45" smd rect
			(at -0.998 1.377 180)
			(size 0.23 0.66)
			(layers "B.Cu" "B.Mask" "B.Paste")
			(net 410 "Net-(Q3-D)")
			(pintype "passive")
		)
		(pad "46" smd rect
			(at -0.998 -1.333 180)
			(size 0.23 0.66)
			(layers "B.Cu" "B.Mask" "B.Paste")
			(net 35 "/Bottom Connector/PCIE.TXD1_P")
			(pintype "passive")
		)
		(pad "47" smd rect
			(at -0.597 1.377 180)
			(size 0.23 0.66)
			(layers "B.Cu" "B.Mask" "B.Paste")
			(net 410 "Net-(Q3-D)")
			(pintype "passive")
		)
		(pad "48" smd rect
			(at -0.597 -1.333 180)
			(size 0.23 0.66)
			(layers "B.Cu" "B.Mask" "B.Paste")
			(net 36 "/Bottom Connector/PCIE.TXD1_N")
			(pintype "passive")
		)
		(pad "49" smd rect
			(at -0.199 1.377 180)
			(size 0.23 0.66)
			(layers "B.Cu" "B.Mask" "B.Paste")
			(net 410 "Net-(Q3-D)")
			(pintype "passive")
		)
		(pad "50" smd rect
			(at -0.199 -1.333 180)
			(size 0.23 0.66)
			(layers "B.Cu" "B.Mask" "B.Paste")
			(net 417 "GND")
			(pintype "passive")
		)
		(pad "51" smd rect
			(at 0.201 1.377 180)
			(size 0.23 0.66)
			(layers "B.Cu" "B.Mask" "B.Paste")
			(net 155 "unconnected-(J4-Pad51)")
			(pintype "passive+no_connect")
		)
		(pad "52" smd rect
			(at 0.201 -1.333 180)
			(size 0.23 0.66)
			(layers "B.Cu" "B.Mask" "B.Paste")
			(net 121 "/Bottom Connector/PCIE.RXD1_P")
			(pintype "passive")
		)
		(pad "53" smd rect
			(at 0.6 1.377 180)
			(size 0.23 0.66)
			(layers "B.Cu" "B.Mask" "B.Paste")
			(net 97 "HDMI0_HOTPLUG")
			(pintype "passive")
		)
		(pad "54" smd rect
			(at 0.6 -1.333 180)
			(size 0.23 0.66)
			(layers "B.Cu" "B.Mask" "B.Paste")
			(net 138 "/Bottom Connector/PCIE.RXD1_N")
			(pintype "passive")
		)
		(pad "55" smd rect
			(at 1 1.377 180)
			(size 0.23 0.66)
			(layers "B.Cu" "B.Mask" "B.Paste")
			(net 417 "GND")
			(pintype "passive")
		)
		(pad "56" smd rect
			(at 1 -1.333 180)
			(size 0.23 0.66)
			(layers "B.Cu" "B.Mask" "B.Paste")
			(net 417 "GND")
			(pintype "passive")
		)
		(pad "57" smd rect
			(at 1.402 1.377 180)
			(size 0.23 0.66)
			(layers "B.Cu" "B.Mask" "B.Paste")
			(net 139 "/Bottom Connector/PCIE.RXD2_N")
			(pintype "passive")
		)
		(pad "58" smd rect
			(at 1.402 -1.333 180)
			(size 0.23 0.66)
			(layers "B.Cu" "B.Mask" "B.Paste")
			(net 37 "/Bottom Connector/PCIE.TXD2_P")
			(pintype "passive")
		)
		(pad "59" smd rect
			(at 1.802 1.377 180)
			(size 0.23 0.66)
			(layers "B.Cu" "B.Mask" "B.Paste")
			(net 140 "/Bottom Connector/PCIE.RXD2_P")
			(pintype "passive")
		)
		(pad "60" smd rect
			(at 1.802 -1.333 180)
			(size 0.23 0.66)
			(layers "B.Cu" "B.Mask" "B.Paste")
			(net 38 "/Bottom Connector/PCIE.TXD2_N")
			(pintype "passive")
		)
		(pad "61" smd rect
			(at 2.203 1.377 180)
			(size 0.23 0.66)
			(layers "B.Cu" "B.Mask" "B.Paste")
			(net 417 "GND")
			(pintype "passive")
		)
		(pad "62" smd rect
			(at 2.203 -1.333 180)
			(size 0.23 0.66)
			(layers "B.Cu" "B.Mask" "B.Paste")
			(net 417 "GND")
			(pintype "passive")
		)
		(pad "63" smd rect
			(at 2.601 1.377 180)
			(size 0.23 0.66)
			(layers "B.Cu" "B.Mask" "B.Paste")
			(net 40 "/Bottom Connector/PCIE.TXD3_N")
			(pintype "passive")
		)
		(pad "64" smd rect
			(at 2.601 -1.333 180)
			(size 0.23 0.66)
			(layers "B.Cu" "B.Mask" "B.Paste")
			(net 141 "/Bottom Connector/PCIE.RXD3_P")
			(pintype "passive")
		)
		(pad "65" smd rect
			(at 3.001 1.377 180)
			(size 0.23 0.66)
			(layers "B.Cu" "B.Mask" "B.Paste")
			(net 39 "/Bottom Connector/PCIE.TXD3_P")
			(pintype "passive")
		)
		(pad "66" smd rect
			(at 3.001 -1.333 180)
			(size 0.23 0.66)
			(layers "B.Cu" "B.Mask" "B.Paste")
			(net 142 "/Bottom Connector/PCIE.RXD3_N")
			(pintype "passive")
		)
		(pad "67" smd rect
			(at 3.401 1.377 180)
			(size 0.23 0.66)
			(layers "B.Cu" "B.Mask" "B.Paste")
			(net 417 "GND")
			(pintype "passive")
		)
		(pad "68" smd rect
			(at 3.401 -1.333 180)
			(size 0.23 0.66)
			(layers "B.Cu" "B.Mask" "B.Paste")
			(net 417 "GND")
			(pintype "passive")
		)
		(pad "69" smd rect
			(at 3.802 1.377 180)
			(size 0.23 0.66)
			(layers "B.Cu" "B.Mask" "B.Paste")
			(net 238 "unconnected-(J4-Pad69)")
			(pintype "passive+no_connect")
		)
		(pad "70" smd rect
			(at 3.802 -1.333 180)
			(size 0.23 0.66)
			(layers "B.Cu" "B.Mask" "B.Paste")
			(net 143 "/Bottom Connector/HDMI0.TX2_P")
			(pintype "passive")
		)
		(pad "71" smd rect
			(at 4.202 1.377 180)
			(size 0.23 0.66)
			(layers "B.Cu" "B.Mask" "B.Paste")
			(net 241 "unconnected-(J4-Pad71)")
			(pintype "passive+no_connect")
		)
		(pad "72" smd rect
			(at 4.202 -1.333 180)
			(size 0.23 0.66)
			(layers "B.Cu" "B.Mask" "B.Paste")
			(net 144 "/Bottom Connector/HDMI0.TX2_N")
			(pintype "passive")
		)
		(pad "73" smd rect
			(at 4.6 1.377 180)
			(size 0.23 0.66)
			(layers "B.Cu" "B.Mask" "B.Paste")
			(net 417 "GND")
			(pintype "passive")
		)
		(pad "74" smd rect
			(at 4.6 -1.333 180)
			(size 0.23 0.66)
			(layers "B.Cu" "B.Mask" "B.Paste")
			(net 417 "GND")
			(pintype "passive")
		)
		(pad "75" smd rect
			(at 5.001 1.377 180)
			(size 0.23 0.66)
			(layers "B.Cu" "B.Mask" "B.Paste")
			(net 146 "/Bottom Connector/DSI1.D0_N")
			(pintype "passive")
		)
		(pad "76" smd rect
			(at 5.001 -1.333 180)
			(size 0.23 0.66)
			(layers "B.Cu" "B.Mask" "B.Paste")
			(net 147 "/Bottom Connector/HDMI0.TX1_P")
			(pintype "passive")
		)
		(pad "77" smd rect
			(at 5.401 1.377 180)
			(size 0.23 0.66)
			(layers "B.Cu" "B.Mask" "B.Paste")
			(net 156 "/Bottom Connector/DSI1.D0_P")
			(pintype "passive")
		)
		(pad "78" smd rect
			(at 5.401 -1.333 180)
			(size 0.23 0.66)
			(layers "B.Cu" "B.Mask" "B.Paste")
			(net 157 "/Bottom Connector/HDMI0.TX1_N")
			(pintype "passive")
		)
		(pad "79" smd rect
			(at 5.802 1.377 180)
			(size 0.23 0.66)
			(layers "B.Cu" "B.Mask" "B.Paste")
			(net 417 "GND")
			(pintype "passive")
		)
		(pad "80" smd rect
			(at 5.802 -1.333 180)
			(size 0.23 0.66)
			(layers "B.Cu" "B.Mask" "B.Paste")
			(net 417 "GND")
			(pintype "passive")
		)
		(pad "81" smd rect
			(at 6.202 1.377 180)
			(size 0.23 0.66)
			(layers "B.Cu" "B.Mask" "B.Paste")
			(net 158 "/Bottom Connector/DSI1.D1_N")
			(pintype "passive")
		)
		(pad "82" smd rect
			(at 6.202 -1.333 180)
			(size 0.23 0.66)
			(layers "B.Cu" "B.Mask" "B.Paste")
			(net 159 "/Bottom Connector/HDMI0.TX0_P")
			(pintype "passive")
		)
		(pad "83" smd rect
			(at 6.6 1.377 180)
			(size 0.23 0.66)
			(layers "B.Cu" "B.Mask" "B.Paste")
			(net 160 "/Bottom Connector/DSI1.D1_P")
			(pintype "passive")
		)
		(pad "84" smd rect
			(at 6.6 -1.333 180)
			(size 0.23 0.66)
			(layers "B.Cu" "B.Mask" "B.Paste")
			(net 161 "/Bottom Connector/HDMI0.TX0_N")
			(pintype "passive")
		)
		(pad "85" smd rect
			(at 7 1.377 180)
			(size 0.23 0.66)
			(layers "B.Cu" "B.Mask" "B.Paste")
			(net 417 "GND")
			(pintype "passive")
		)
		(pad "86" smd rect
			(at 7 -1.333 180)
			(size 0.23 0.66)
			(layers "B.Cu" "B.Mask" "B.Paste")
			(net 417 "GND")
			(pintype "passive")
		)
		(pad "87" smd rect
			(at 7.401 1.377 180)
			(size 0.23 0.66)
			(layers "B.Cu" "B.Mask" "B.Paste")
			(net 162 "/Bottom Connector/DSI1.C_N")
			(pintype "passive")
		)
		(pad "88" smd rect
			(at 7.401 -1.333 180)
			(size 0.23 0.66)
			(layers "B.Cu" "B.Mask" "B.Paste")
			(net 163 "/Bottom Connector/HDMI0.CLK_P")
			(pintype "passive")
		)
		(pad "89" smd rect
			(at 7.802 1.377 180)
			(size 0.23 0.66)
			(layers "B.Cu" "B.Mask" "B.Paste")
			(net 195 "/Bottom Connector/DSI1.C_P")
			(pintype "passive")
		)
		(pad "90" smd rect
			(at 7.802 -1.333 180)
			(size 0.23 0.66)
			(layers "B.Cu" "B.Mask" "B.Paste")
			(net 196 "/Bottom Connector/HDMI0.CLK_N")
			(pintype "passive")
		)
		(pad "91" smd rect
			(at 8.2 1.377 180)
			(size 0.23 0.66)
			(layers "B.Cu" "B.Mask" "B.Paste")
			(net 417 "GND")
			(pintype "passive")
		)
		(pad "92" smd rect
			(at 8.2 -1.333 180)
			(size 0.23 0.66)
			(layers "B.Cu" "B.Mask" "B.Paste")
			(net 417 "GND")
			(pintype "passive")
		)
		(pad "93" smd rect
			(at 8.6 1.377 180)
			(size 0.23 0.66)
			(layers "B.Cu" "B.Mask" "B.Paste")
			(net 197 "/Bottom Connector/DSI1.D2_N")
			(pintype "passive")
		)
		(pad "94" smd rect
			(at 8.6 -1.333 180)
			(size 0.23 0.66)
			(layers "B.Cu" "B.Mask" "B.Paste")
			(net 198 "/Bottom Connector/DSI1.D3_N")
			(pintype "passive")
		)
	)
)
